# BASEBOARD_FAB2 (Tioga Pass) — schematic netlist excerpt (pin names and nets, part order shuffled) for the footprints in the layout excerpt that follows; sources: Cadence DE-HDL packaged netlist, KiCad conversion of Wiwynn_Tioga_Pass_MB.brd

R4A4  RES  33.2 1% CHIP  pkg 0402  page 230 : A = PWRGD_PVTT_KLM_CPU1_R ; B = PWRGD_PVTT_CPU1
C1A6  CAP  1.0UF 16V 10% X6S  pkg 0402  page 227 : A = VR_PVDDQ_KLM_PH2_VCIN ; B = GND
R1B15  RES  3.16K 1% CHIP  pkg 0402  page 226 : A = VR_PVDDQ_KLM_XADDR2 ; B = GND

(kicad_pcb
	(version 20260206)
	(generator "pcbnew")
	(generator_version "10.0")
	(general
		(thickness 1.6)
		(legacy_teardrops no)
	)
	(paper "A4")
	(title_block
		(title "Wiwynn_Tioga_Pass_MB.brd")
		(comment 1 "Tioga Pass / footprints 2204-2206 of 4770")
	)
	(layers
		(0 "F.Cu" signal "TOP")
		(4 "In1.Cu" signal "L2GND")
		(6 "In2.Cu" signal "L3")
		(8 "In3.Cu" signal "L4GND")
		(10 "In4.Cu" signal "L5")
		(12 "In5.Cu" signal "L6GND")
		(14 "In6.Cu" signal "L7VCC")
		(16 "In7.Cu" signal "L8VCC")
		(18 "In8.Cu" signal "L9GND")
		(20 "In9.Cu" signal "L10")
		(22 "In10.Cu" signal "L11GND")
		(24 "In11.Cu" signal "L12")
		(26 "In12.Cu" signal "L13GND")
		(2 "B.Cu" signal "BOTTOM")
		(9 "F.Adhes" user "F.Adhesive")
		(11 "B.Adhes" user "B.Adhesive")
		(13 "F.Paste" user "Package Geometry/Pastemask Top")
		(15 "B.Paste" user "Package Geometry/Pastemask Bottom")
		(5 "F.SilkS" user "Ref Des/Silkscreen Top")
		(7 "B.SilkS" user "Ref Des/Silkscreen Bottom")
		(1 "F.Mask" user "Board Geometry/Soldermask Top")
		(3 "B.Mask" user "Board Geometry/Soldermask Bottom")
		(17 "Dwgs.User" user "User.Drawings")
		(19 "Cmts.User" user "User.Comments")
		(21 "Eco1.User" user "User.Eco1")
		(23 "Eco2.User" user "User.Eco2")
		(25 "Edge.Cuts" user "Board Geometry/Outline")
		(27 "Margin" user)
		(31 "F.CrtYd" user "Package Geometry/Place Bound Top")
		(29 "B.CrtYd" user "Package Geometry/Place Bound Bottom")
		(35 "F.Fab" user "Ref Des/Assembly Top")
		(33 "B.Fab" user "Ref Des/Assembly Bottom")
	)
	(footprint ""
		(layer "F.Cu")
		(at 174.3583 -150.114 90)
		(property "Reference" "R4A4"
			(at 0 0 90)
			(layer "F.SilkS")
			(hide yes)
			(effects
				(font
					(size 1.27 1.27)
				)
			)
		)
		(property "Value" ""
			(at 0 0 90)
			(layer "F.Fab")
			(effects
				(font
					(size 1.27 1.27)
				)
			)
		)
		(duplicate_pad_numbers_are_jumpers no)
		(fp_poly
			(pts
				(xy -0.2794 -0.1016) (xy 0.2794 -0.1016) (xy 0.2794 0.9906) (xy -0.2794 0.9906)
			)
			(stroke
				(width 0)
				(type default)
			)
			(fill no)
			(layer "F.CrtYd")
		)
		(fp_line
			(start 0.2794 -0.1016)
			(end -0.2794 -0.1016)
			(stroke
				(width 0.1)
				(type default)
			)
			(layer "F.Fab")
		)
		(fp_line
			(start -0.2794 -0.1016)
			(end -0.2794 0.9906)
			(stroke
				(width 0.1)
				(type default)
			)
			(layer "F.Fab")
		)
		(fp_line
			(start 0.2794 0.9906)
			(end 0.2794 -0.1016)
			(stroke
				(width 0.1)
				(type default)
			)
			(layer "F.Fab")
		)
		(fp_line
			(start -0.2794 0.9906)
			(end 0.2794 0.9906)
			(stroke
				(width 0.1)
				(type default)
			)
			(layer "F.Fab")
		)
		(pad "1" smd rect
			(at 0 0 90)
			(size 0.508 0.508)
			(layers "F.Cu" "F.Mask" "F.Paste")
			(net "PWRGD_PVTT_KLM_CPU1_R")
		)
		(pad "2" smd rect
			(at 0 0.889 90)
			(size 0.508 0.508)
			(layers "F.Cu" "F.Mask" "F.Paste")
			(net "PWRGD_PVTT_CPU1")
		)
		(zone
			(layer "F.Cu")
			(hatch none 0.5)
			(connect_pads
				(clearance 0)
			)
			(min_thickness 0.25)
			(keepout
				(tracks allowed)
				(vias not_allowed)
				(pads allowed)
				(copperpour not_allowed)
				(footprints allowed)
			)
			(placement
				(enabled no)
				(sheetname "")
			)
			(fill
				(thermal_gap 0.5)
				(thermal_bridge_width 0.5)
				(island_removal_mode 0)
			)
			(polygon
				(pts
					(xy 174.6123 -149.86) (xy 174.6123 -150.368) (xy 174.9933 -150.368) (xy 174.9933 -149.86)
				)
			)
		)
		(zone
			(layer "F.Cu")
			(hatch none 0.5)
			(connect_pads
				(clearance 0)
			)
			(min_thickness 0.25)
			(keepout
				(tracks not_allowed)
				(vias allowed)
				(pads allowed)
				(copperpour not_allowed)
				(footprints allowed)
			)
			(placement
				(enabled no)
				(sheetname "")
			)
			(fill
				(thermal_gap 0.5)
				(thermal_bridge_width 0.5)
				(island_removal_mode 0)
			)
			(polygon
				(pts
					(xy 174.9933 -149.86) (xy 174.9933 -150.368) (xy 174.6123 -150.368) (xy 174.6123 -149.86)
				)
			)
		)
	)
	(footprint ""
		(layer "F.Cu")
		(at 6.35 -125.095 90)
		(property "Reference" "R1B15"
			(at 0 0 90)
			(layer "F.SilkS")
			(hide yes)
			(effects
				(font
					(size 1.27 1.27)
				)
			)
		)
		(property "Value" ""
			(at 0 0 90)
			(layer "F.Fab")
			(effects
				(font
					(size 1.27 1.27)
				)
			)
		)
		(duplicate_pad_numbers_are_jumpers no)
		(fp_poly
			(pts
				(xy -0.2794 -0.1016) (xy 0.2794 -0.1016) (xy 0.2794 0.9906) (xy -0.2794 0.9906)
			)
			(stroke
				(width 0)
				(type default)
			)
			(fill no)
			(layer "F.CrtYd")
		)
		(fp_line
			(start 0.2794 -0.1016)
			(end -0.2794 -0.1016)
			(stroke
				(width 0.1)
				(type default)
			)
			(layer "F.Fab")
		)
		(fp_line
			(start -0.2794 -0.1016)
			(end -0.2794 0.9906)
			(stroke
				(width 0.1)
				(type default)
			)
			(layer "F.Fab")
		)
		(fp_line
			(start 0.2794 0.9906)
			(end 0.2794 -0.1016)
			(stroke
				(width 0.1)
				(type default)
			)
			(layer "F.Fab")
		)
		(fp_line
			(start -0.2794 0.9906)
			(end 0.2794 0.9906)
			(stroke
				(width 0.1)
				(type default)
			)
			(layer "F.Fab")
		)
		(pad "1" smd rect
			(at 0 0 90)
			(size 0.508 0.508)
			(layers "F.Cu" "F.Mask" "F.Paste")
			(net "VR_PVDDQ_KLM_XADDR2")
		)
		(pad "2" smd rect
			(at 0 0.889 90)
			(size 0.508 0.508)
			(layers "F.Cu" "F.Mask" "F.Paste")
			(net "GND")
		)
		(zone
			(layer "F.Cu")
			(hatch none 0.5)
			(connect_pads
				(clearance 0)
			)
			(min_thickness 0.25)
			(keepout
				(tracks allowed)
				(vias not_allowed)
				(pads allowed)
				(copperpour not_allowed)
				(footprints allowed)
			)
			(placement
				(enabled no)
				(sheetname "")
			)
			(fill
				(thermal_gap 0.5)
				(thermal_bridge_width 0.5)
				(island_removal_mode 0)
			)
			(polygon
				(pts
					(xy 6.604 -124.841) (xy 6.604 -125.349) (xy 6.985 -125.349) (xy 6.985 -124.841)
				)
			)
		)
		(zone
			(layer "F.Cu")
			(hatch none 0.5)
			(connect_pads
				(clearance 0)
			)
			(min_thickness 0.25)
			(keepout
				(tracks not_allowed)
				(vias allowed)
				(pads allowed)
				(copperpour not_allowed)
				(footprints allowed)
			)
			(placement
				(enabled no)
				(sheetname "")
			)
			(fill
				(thermal_gap 0.5)
				(thermal_bridge_width 0.5)
				(island_removal_mode 0)
			)
			(polygon
				(pts
					(xy 6.985 -124.841) (xy 6.985 -125.349) (xy 6.604 -125.349) (xy 6.604 -124.841)
				)
			)
		)
	)
	(footprint ""
		(layer "F.Cu")
		(at 0.635 -143.256 -90)
		(property "Reference" "C1A6"
			(at 0 0 270)
			(layer "F.SilkS")
			(hide yes)
			(effects
				(font
					(size 1.27 1.27)
				)
			)
		)
		(property "Value" ""
			(at 0 0 270)
			(layer "F.Fab")
			(effects
				(font
					(size 1.27 1.27)
				)
			)
		)
		(duplicate_pad_numbers_are_jumpers no)
		(fp_poly
			(pts
				(xy 0.3048 -0.1016) (xy 0.3048 0.9906) (xy -0.3048 0.9906) (xy -0.3048 -0.1016)
			)
			(stroke
				(width 0)
				(type default)
			)
			(fill no)
			(layer "F.CrtYd")
		)
		(fp_line
			(start -0.3048 0.9906)
			(end 0.3048 0.9906)
			(stroke
				(width 0.1)
				(type default)
			)
			(layer "F.Fab")
		)
		(fp_line
			(start 0.3048 0.9906)
			(end 0.3048 -0.1016)
			(stroke
				(width 0.1)
				(type default)
			)
			(layer "F.Fab")
		)
		(fp_line
			(start -0.3048 -0.1016)
			(end -0.3048 0.9906)
			(stroke
				(width 0.1)
				(type default)
			)
			(layer "F.Fab")
		)
		(fp_line
			(start 0.3048 -0.1016)
			(end -0.3048 -0.1016)
			(stroke
				(width 0.1)
				(type default)
			)
			(layer "F.Fab")
		)
		(pad "1" smd rect
			(at 0 0 270)
			(size 0.508 0.508)
			(layers "F.Cu" "F.Mask" "F.Paste")
			(net "VR_PVDDQ_KLM_PH2_VCIN")
		)
		(pad "2" smd rect
			(at 0 0.889 270)
			(size 0.508 0.508)
			(layers "F.Cu" "F.Mask" "F.Paste")
			(net "GND")
		)
		(zone
			(layer "F.Cu")
			(hatch none 0.5)
			(connect_pads
				(clearance 0)
			)
			(min_thickness 0.25)
			(keepout
				(tracks not_allowed)
				(vias allowed)
				(pads allowed)
				(copperpour not_allowed)
				(footprints allowed)
			)
			(placement
				(enabled no)
				(sheetname "")
			)
			(fill
				(thermal_gap 0.5)
				(thermal_bridge_width 0.5)
				(island_removal_mode 0)
			)
			(polygon
				(pts
					(xy 0 -143.51) (xy 0 -143.002) (xy 0.381 -143.002) (xy 0.381 -143.51)
				)
			)
		)
		(zone
			(layer "F.Cu")
			(hatch none 0.5)
			(connect_pads
				(clearance 0)
			)
			(min_thickness 0.25)
			(keepout
				(tracks allowed)
				(vias not_allowed)
				(pads allowed)
				(copperpour not_allowed)
				(footprints allowed)
			)
			(placement
				(enabled no)
				(sheetname "")
			)
			(fill
				(thermal_gap 0.5)
				(thermal_bridge_width 0.5)
				(island_removal_mode 0)
			)
			(polygon
				(pts
					(xy 0.381 -143.51) (xy 0.381 -143.002) (xy 0 -143.002) (xy 0 -143.51)
				)
			)
		)
	)
)
